# BASEBOARD_FAB2 (Tioga Pass) — schematic netlist excerpt (pin names and nets, part order shuffled) for the footprints in the layout excerpt that follows; sources: Cadence DE-HDL packaged netlist, KiCad conversion of Wiwynn_Tioga_Pass_MB.brd

C7C13  CAP  15.0PF 50V 5% COG  pkg 0402LF  page 114 : A = XTAL_33K_RTC1 ; B = GND
C6B17  CAP  0.22UF 16V 10% X7R  pkg 0402  page 105 : A = P3E_CPU0_PE1_PCH_TXN<9> ; B = P3E_CPU0_PE1_PCH_C_TXN<9>
R6W41  RES  4.75K 1% CHIP  pkg 0402  page 164 : A = P3V3_STBY ; B = PCA9554_INT_N

(kicad_pcb
	(version 20260206)
	(generator "pcbnew")
	(generator_version "10.0")
	(general
		(thickness 1.6)
		(legacy_teardrops no)
	)
	(paper "A4")
	(title_block
		(title "Wiwynn_Tioga_Pass_MB.brd")
		(comment 1 "Tioga Pass / footprints 463-465 of 4770")
	)
	(layers
		(0 "F.Cu" signal "TOP")
		(4 "In1.Cu" signal "L2GND")
		(6 "In2.Cu" signal "L3")
		(8 "In3.Cu" signal "L4GND")
		(10 "In4.Cu" signal "L5")
		(12 "In5.Cu" signal "L6GND")
		(14 "In6.Cu" signal "L7VCC")
		(16 "In7.Cu" signal "L8VCC")
		(18 "In8.Cu" signal "L9GND")
		(20 "In9.Cu" signal "L10")
		(22 "In10.Cu" signal "L11GND")
		(24 "In11.Cu" signal "L12")
		(26 "In12.Cu" signal "L13GND")
		(2 "B.Cu" signal "BOTTOM")
		(9 "F.Adhes" user "F.Adhesive")
		(11 "B.Adhes" user "B.Adhesive")
		(13 "F.Paste" user "Package Geometry/Pastemask Top")
		(15 "B.Paste" user "Package Geometry/Pastemask Bottom")
		(5 "F.SilkS" user "Ref Des/Silkscreen Top")
		(7 "B.SilkS" user "Ref Des/Silkscreen Bottom")
		(1 "F.Mask" user "Board Geometry/Soldermask Top")
		(3 "B.Mask" user "Board Geometry/Soldermask Bottom")
		(17 "Dwgs.User" user "User.Drawings")
		(19 "Cmts.User" user "User.Comments")
		(21 "Eco1.User" user "User.Eco1")
		(23 "Eco2.User" user "User.Eco2")
		(25 "Edge.Cuts" user "Board Geometry/Outline")
		(27 "Margin" user)
		(31 "F.CrtYd" user "Package Geometry/Place Bound Top")
		(29 "B.CrtYd" user "Package Geometry/Place Bound Bottom")
		(35 "F.Fab" user "Ref Des/Assembly Top")
		(33 "B.Fab" user "Ref Des/Assembly Bottom")
	)
	(footprint ""
		(layer "F.Cu")
		(at 339.222588 -119.211598 90)
		(property "Reference" "C6B17"
			(at -0.8382 -0.67818 90)
			(unlocked yes)
			(layer "F.SilkS")
			(effects
				(font
					(size 0.4064 0.254)
					(thickness 0.1524)
				)
				(justify left)
			)
		)
		(property "Value" ""
			(at 0 0 90)
			(layer "F.Fab")
			(effects
				(font
					(size 1.27 1.27)
				)
			)
		)
		(duplicate_pad_numbers_are_jumpers no)
		(fp_poly
			(pts
				(xy 0.3048 -0.1016) (xy 0.3048 0.9906) (xy -0.3048 0.9906) (xy -0.3048 -0.1016)
			)
			(stroke
				(width 0)
				(type default)
			)
			(fill no)
			(layer "F.CrtYd")
		)
		(fp_line
			(start 0.3048 -0.1016)
			(end -0.3048 -0.1016)
			(stroke
				(width 0.1)
				(type default)
			)
			(layer "F.Fab")
		)
		(fp_line
			(start -0.3048 -0.1016)
			(end -0.3048 0.9906)
			(stroke
				(width 0.1)
				(type default)
			)
			(layer "F.Fab")
		)
		(fp_line
			(start 0.3048 0.9906)
			(end 0.3048 -0.1016)
			(stroke
				(width 0.1)
				(type default)
			)
			(layer "F.Fab")
		)
		(fp_line
			(start -0.3048 0.9906)
			(end 0.3048 0.9906)
			(stroke
				(width 0.1)
				(type default)
			)
			(layer "F.Fab")
		)
		(pad "1" smd rect
			(at 0 0 90)
			(size 0.508 0.508)
			(layers "F.Cu" "F.Mask" "F.Paste")
			(net "P3E_CPU0_PE1_PCH_TXN<9>")
		)
		(pad "2" smd rect
			(at 0 0.889 90)
			(size 0.508 0.508)
			(layers "F.Cu" "F.Mask" "F.Paste")
			(net "P3E_CPU0_PE1_PCH_C_TXN<9>")
		)
		(zone
			(layer "F.Cu")
			(hatch none 0.5)
			(connect_pads
				(clearance 0)
			)
			(min_thickness 0.25)
			(keepout
				(tracks allowed)
				(vias not_allowed)
				(pads allowed)
				(copperpour not_allowed)
				(footprints allowed)
			)
			(placement
				(enabled no)
				(sheetname "")
			)
			(fill
				(thermal_gap 0.5)
				(thermal_bridge_width 0.5)
				(island_removal_mode 0)
			)
			(polygon
				(pts
					(xy 339.476588 -118.957598) (xy 339.476588 -119.465598) (xy 339.857588 -119.465598) (xy 339.857588 -118.957598)
				)
			)
		)
		(zone
			(layer "F.Cu")
			(hatch none 0.5)
			(connect_pads
				(clearance 0)
			)
			(min_thickness 0.25)
			(keepout
				(tracks not_allowed)
				(vias allowed)
				(pads allowed)
				(copperpour not_allowed)
				(footprints allowed)
			)
			(placement
				(enabled no)
				(sheetname "")
			)
			(fill
				(thermal_gap 0.5)
				(thermal_bridge_width 0.5)
				(island_removal_mode 0)
			)
			(polygon
				(pts
					(xy 339.857588 -118.957598) (xy 339.857588 -119.465598) (xy 339.476588 -119.465598) (xy 339.476588 -118.957598)
				)
			)
		)
	)
	(footprint ""
		(layer "F.Cu")
		(at 369.2906 -100.2284 180)
		(property "Reference" "C7C13"
			(at 0 0 180)
			(layer "F.SilkS")
			(hide yes)
			(effects
				(font
					(size 1.27 1.27)
				)
			)
		)
		(property "Value" ""
			(at 0 0 180)
			(layer "F.Fab")
			(effects
				(font
					(size 1.27 1.27)
				)
			)
		)
		(duplicate_pad_numbers_are_jumpers no)
		(fp_poly
			(pts
				(xy 0.3048 -0.1016) (xy 0.3048 0.9906) (xy -0.3048 0.9906) (xy -0.3048 -0.1016)
			)
			(stroke
				(width 0)
				(type default)
			)
			(fill no)
			(layer "F.CrtYd")
		)
		(fp_line
			(start 0.3048 0.9906)
			(end 0.3048 -0.1016)
			(stroke
				(width 0.1)
				(type default)
			)
			(layer "F.Fab")
		)
		(fp_line
			(start 0.3048 -0.1016)
			(end -0.3048 -0.1016)
			(stroke
				(width 0.1)
				(type default)
			)
			(layer "F.Fab")
		)
		(fp_line
			(start -0.3048 0.9906)
			(end 0.3048 0.9906)
			(stroke
				(width 0.1)
				(type default)
			)
			(layer "F.Fab")
		)
		(fp_line
			(start -0.3048 -0.1016)
			(end -0.3048 0.9906)
			(stroke
				(width 0.1)
				(type default)
			)
			(layer "F.Fab")
		)
		(pad "1" smd rect
			(at 0 0 180)
			(size 0.508 0.508)
			(layers "F.Cu" "F.Mask" "F.Paste")
			(net "XTAL_33K_RTC1")
		)
		(pad "2" smd rect
			(at 0 0.889 180)
			(size 0.508 0.508)
			(layers "F.Cu" "F.Mask" "F.Paste")
			(net "GND")
		)
		(zone
			(layer "F.Cu")
			(hatch none 0.5)
			(connect_pads
				(clearance 0)
			)
			(min_thickness 0.25)
			(keepout
				(tracks not_allowed)
				(vias allowed)
				(pads allowed)
				(copperpour not_allowed)
				(footprints allowed)
			)
			(placement
				(enabled no)
				(sheetname "")
			)
			(fill
				(thermal_gap 0.5)
				(thermal_bridge_width 0.5)
				(island_removal_mode 0)
			)
			(polygon
				(pts
					(xy 369.5446 -100.8634) (xy 369.0366 -100.8634) (xy 369.0366 -100.4824) (xy 369.5446 -100.4824)
				)
			)
		)
		(zone
			(layer "F.Cu")
			(hatch none 0.5)
			(connect_pads
				(clearance 0)
			)
			(min_thickness 0.25)
			(keepout
				(tracks allowed)
				(vias not_allowed)
				(pads allowed)
				(copperpour not_allowed)
				(footprints allowed)
			)
			(placement
				(enabled no)
				(sheetname "")
			)
			(fill
				(thermal_gap 0.5)
				(thermal_bridge_width 0.5)
				(island_removal_mode 0)
			)
			(polygon
				(pts
					(xy 369.5446 -100.4824) (xy 369.0366 -100.4824) (xy 369.0366 -100.8634) (xy 369.5446 -100.8634)
				)
			)
		)
	)
	(footprint ""
		(layer "F.Cu")
		(at 423.650664 -13.872464 180)
		(property "Reference" "R6W41"
			(at -0.8382 -0.67818 180)
			(unlocked yes)
			(layer "F.SilkS")
			(effects
				(font
					(size 0.4064 0.254)
					(thickness 0.1524)
				)
				(justify left)
			)
		)
		(property "Value" ""
			(at 0 0 180)
			(layer "F.Fab")
			(effects
				(font
					(size 1.27 1.27)
				)
			)
		)
		(duplicate_pad_numbers_are_jumpers no)
		(fp_poly
			(pts
				(xy -0.2794 -0.1016) (xy 0.2794 -0.1016) (xy 0.2794 0.9906) (xy -0.2794 0.9906)
			)
			(stroke
				(width 0)
				(type default)
			)
			(fill no)
			(layer "F.CrtYd")
		)
		(fp_line
			(start 0.2794 0.9906)
			(end 0.2794 -0.1016)
			(stroke
				(width 0.1)
				(type default)
			)
			(layer "F.Fab")
		)
		(fp_line
			(start 0.2794 -0.1016)
			(end -0.2794 -0.1016)
			(stroke
				(width 0.1)
				(type default)
			)
			(layer "F.Fab")
		)
		(fp_line
			(start -0.2794 0.9906)
			(end 0.2794 0.9906)
			(stroke
				(width 0.1)
				(type default)
			)
			(layer "F.Fab")
		)
		(fp_line
			(start -0.2794 -0.1016)
			(end -0.2794 0.9906)
			(stroke
				(width 0.1)
				(type default)
			)
			(layer "F.Fab")
		)
		(pad "1" smd rect
			(at 0 0 180)
			(size 0.508 0.508)
			(layers "F.Cu" "F.Mask" "F.Paste")
			(net "P3V3_STBY")
		)
		(pad "2" smd rect
			(at 0 0.889 180)
			(size 0.508 0.508)
			(layers "F.Cu" "F.Mask" "F.Paste")
			(net "PCA9554_INT_N")
		)
		(zone
			(layer "F.Cu")
			(hatch none 0.5)
			(connect_pads
				(clearance 0)
			)
			(min_thickness 0.25)
			(keepout
				(tracks not_allowed)
				(vias allowed)
				(pads allowed)
				(copperpour not_allowed)
				(footprints allowed)
			)
			(placement
				(enabled no)
				(sheetname "")
			)
			(fill
				(thermal_gap 0.5)
				(thermal_bridge_width 0.5)
				(island_removal_mode 0)
			)
			(polygon
				(pts
					(xy 423.904664 -14.507464) (xy 423.396664 -14.507464) (xy 423.396664 -14.126464) (xy 423.904664 -14.126464)
				)
			)
		)
		(zone
			(layer "F.Cu")
			(hatch none 0.5)
			(connect_pads
				(clearance 0)
			)
			(min_thickness 0.25)
			(keepout
				(tracks allowed)
				(vias not_allowed)
				(pads allowed)
				(copperpour not_allowed)
				(footprints allowed)
			)
			(placement
				(enabled no)
				(sheetname "")
			)
			(fill
				(thermal_gap 0.5)
				(thermal_bridge_width 0.5)
				(island_removal_mode 0)
			)
			(polygon
				(pts
					(xy 423.904664 -14.126464) (xy 423.396664 -14.126464) (xy 423.396664 -14.507464) (xy 423.904664 -14.507464)
				)
			)
		)
	)
)
